(kicad_pcb
	(version 20260206)
	(generator "pcbnew")
	(generator_version "10.0")
	(general
		(thickness 1.6)
		(legacy_teardrops no)
	)
	(paper "A4")
	(title_block
		(title "03242023_DA0F0TMBIJ0_F0T_Motherboard_J_brd_V01_OCP.brd")
		(comment 1 "Grand Teton / footprint 1236 of 6105 (J1), pads 1-112 of 291")
	)
	(layers
		(0 "F.Cu" signal "TOP")
		(4 "In1.Cu" signal "GND")
		(6 "In2.Cu" signal "IN1")
		(8 "In3.Cu" signal "GND1")
		(10 "In4.Cu" signal "IN2")
		(12 "In5.Cu" signal "GND2")
		(14 "In6.Cu" signal "IN3")
		(16 "In7.Cu" signal "GND3")
		(18 "In8.Cu" signal "VCC")
		(20 "In9.Cu" signal "VCC1")
		(22 "In10.Cu" signal "GND4")
		(24 "In11.Cu" signal "IN4")
		(26 "In12.Cu" signal "GND5")
		(28 "In13.Cu" signal "IN5")
		(30 "In14.Cu" signal "GND6")
		(32 "In15.Cu" signal "IN6")
		(34 "In16.Cu" signal "GND7")
		(2 "B.Cu" signal "BOTTOM")
		(9 "F.Adhes" user "F.Adhesive")
		(11 "B.Adhes" user "B.Adhesive")
		(13 "F.Paste" user "Package Geometry/Pastemask Top")
		(15 "B.Paste" user "Package Geometry/Pastemask Bottom")
		(5 "F.SilkS" user "Ref Des/Silkscreen Top")
		(7 "B.SilkS" user "Ref Des/Silkscreen Bottom")
		(1 "F.Mask" user "Board Geometry/Soldermask Top")
		(3 "B.Mask" user "Board Geometry/Soldermask Bottom")
		(17 "Dwgs.User" user "User.Drawings")
		(19 "Cmts.User" user "User.Comments")
		(21 "Eco1.User" user "User.Eco1")
		(23 "Eco2.User" user "User.Eco2")
		(25 "Edge.Cuts" user "Board Geometry/Outline")
		(27 "Margin" user)
		(31 "F.CrtYd" user "Package Geometry/Place Bound Top")
		(29 "B.CrtYd" user "Package Geometry/Place Bound Bottom")
		(35 "F.Fab" user "Ref Des/Assembly Top")
		(33 "B.Fab" user "Ref Des/Assembly Bottom")
	)
	(footprint ""
		(layer "F.Cu")
		(at 303.393348 -258.091686)
		(property "Reference" "J1"
			(at -3.683 -81.702148 0)
			(unlocked yes)
			(layer "F.SilkS")
			(effects
				(font
					(size 0.7874 0.5842)
					(thickness 0.1524)
				)
				(justify left)
			)
		)
		(property "Value" ""
			(at 0 0 0)
			(layer "F.Fab")
			(effects
				(font
					(size 1.27 1.27)
				)
			)
		)
		(duplicate_pad_numbers_are_jumpers no)
		(pad "1" smd rect
			(at -2.050034 -63.324994 270)
			(size 0.519938 1.4986)
			(layers "F.Cu" "F.Mask" "F.Paste")
			(net "P12V_S3_AUX_CPU0_NVDIMM")
		)
		(pad "2" smd rect
			(at -2.050034 -62.47511 270)
			(size 0.519938 1.4986)
			(layers "F.Cu" "F.Mask" "F.Paste")
			(net "TP_CHA_CPU0_DIMM1_FRU_0")
		)
		(pad "3" smd rect
			(at -2.050034 -61.624972 270)
			(size 0.519938 1.4986)
			(layers "F.Cu" "F.Mask" "F.Paste")
			(net "P3V3_AUX")
		)
		(pad "4" smd rect
			(at -2.050034 -60.775088 270)
			(size 0.519938 1.4986)
			(layers "F.Cu" "F.Mask" "F.Paste")
			(net "I3C_SPD_DDRABCD_CPU0_LVC1_SCL_R")
		)
		(pad "5" smd rect
			(at -2.050034 -59.92495 270)
			(size 0.519938 1.4986)
			(layers "F.Cu" "F.Mask" "F.Paste")
			(net "I3C_SPD_DDRABCD_CPU0_LVC1_SDA")
		)
		(pad "6" smd rect
			(at -2.050034 -59.075066 270)
			(size 0.519938 1.4986)
			(layers "F.Cu" "F.Mask" "F.Paste")
			(net "GND")
		)
		(pad "7" smd rect
			(at -2.050034 -58.224928 270)
			(size 0.519938 1.4986)
			(layers "F.Cu" "F.Mask" "F.Paste")
			(net "M_A_CPU0_SA_DQ<0>")
		)
		(pad "8" smd rect
			(at -2.050034 -57.375044 270)
			(size 0.519938 1.4986)
			(layers "F.Cu" "F.Mask" "F.Paste")
			(net "GND")
		)
		(pad "9" smd rect
			(at -2.050034 -56.524906 270)
			(size 0.519938 1.4986)
			(layers "F.Cu" "F.Mask" "F.Paste")
			(net "M_A_CPU0_SA_DQ<1>")
		)
		(pad "10" smd rect
			(at -2.050034 -55.675022 270)
			(size 0.519938 1.4986)
			(layers "F.Cu" "F.Mask" "F.Paste")
			(net "GND")
		)
		(pad "11" smd rect
			(at -2.050034 -54.824884 270)
			(size 0.519938 1.4986)
			(layers "F.Cu" "F.Mask" "F.Paste")
			(net "M_A_CPU0_SA_DQS_DP<0>")
		)
		(pad "12" smd rect
			(at -2.050034 -53.975 270)
			(size 0.519938 1.4986)
			(layers "F.Cu" "F.Mask" "F.Paste")
			(net "M_A_CPU0_SA_DQS_DN<0>")
		)
		(pad "13" smd rect
			(at -2.050034 -53.125116 270)
			(size 0.519938 1.4986)
			(layers "F.Cu" "F.Mask" "F.Paste")
			(net "GND")
		)
		(pad "14" smd rect
			(at -2.050034 -52.274978 270)
			(size 0.519938 1.4986)
			(layers "F.Cu" "F.Mask" "F.Paste")
			(net "M_A_CPU0_SA_DQ<4>")
		)
		(pad "15" smd rect
			(at -2.050034 -51.425094 270)
			(size 0.519938 1.4986)
			(layers "F.Cu" "F.Mask" "F.Paste")
			(net "GND")
		)
		(pad "16" smd rect
			(at -2.050034 -50.574956 270)
			(size 0.519938 1.4986)
			(layers "F.Cu" "F.Mask" "F.Paste")
			(net "M_A_CPU0_SA_DQ<5>")
		)
		(pad "17" smd rect
			(at -2.050034 -49.725072 270)
			(size 0.519938 1.4986)
			(layers "F.Cu" "F.Mask" "F.Paste")
			(net "GND")
		)
		(pad "18" smd rect
			(at -2.050034 -48.874934 270)
			(size 0.519938 1.4986)
			(layers "F.Cu" "F.Mask" "F.Paste")
			(net "M_A_CPU0_SA_DQ<8>")
		)
		(pad "19" smd rect
			(at -2.050034 -48.02505 270)
			(size 0.519938 1.4986)
			(layers "F.Cu" "F.Mask" "F.Paste")
			(net "GND")
		)
		(pad "20" smd rect
			(at -2.050034 -47.174912 270)
			(size 0.519938 1.4986)
			(layers "F.Cu" "F.Mask" "F.Paste")
			(net "M_A_CPU0_SA_DQ<9>")
		)
		(pad "21" smd rect
			(at -2.050034 -46.325028 270)
			(size 0.519938 1.4986)
			(layers "F.Cu" "F.Mask" "F.Paste")
			(net "GND")
		)
		(pad "22" smd rect
			(at -2.050034 -45.47489 270)
			(size 0.519938 1.4986)
			(layers "F.Cu" "F.Mask" "F.Paste")
			(net "M_A_CPU0_SA_DQS_DP<1>")
		)
		(pad "23" smd rect
			(at -2.050034 -44.625006 270)
			(size 0.519938 1.4986)
			(layers "F.Cu" "F.Mask" "F.Paste")
			(net "M_A_CPU0_SA_DQS_DN<1>")
		)
		(pad "24" smd rect
			(at -2.050034 -43.775122 270)
			(size 0.519938 1.4986)
			(layers "F.Cu" "F.Mask" "F.Paste")
			(net "GND")
		)
		(pad "25" smd rect
			(at -2.050034 -42.924984 270)
			(size 0.519938 1.4986)
			(layers "F.Cu" "F.Mask" "F.Paste")
			(net "M_A_CPU0_SA_DQ<12>")
		)
		(pad "26" smd rect
			(at -2.050034 -42.0751 270)
			(size 0.519938 1.4986)
			(layers "F.Cu" "F.Mask" "F.Paste")
			(net "GND")
		)
		(pad "27" smd rect
			(at -2.050034 -41.224962 270)
			(size 0.519938 1.4986)
			(layers "F.Cu" "F.Mask" "F.Paste")
			(net "M_A_CPU0_SA_DQ<13>")
		)
		(pad "28" smd rect
			(at -2.050034 -40.375078 270)
			(size 0.519938 1.4986)
			(layers "F.Cu" "F.Mask" "F.Paste")
			(net "GND")
		)
		(pad "29" smd rect
			(at -2.050034 -39.52494 270)
			(size 0.519938 1.4986)
			(layers "F.Cu" "F.Mask" "F.Paste")
			(net "M_A_CPU0_SA_DQ<16>")
		)
		(pad "30" smd rect
			(at -2.050034 -38.675056 270)
			(size 0.519938 1.4986)
			(layers "F.Cu" "F.Mask" "F.Paste")
			(net "GND")
		)
		(pad "31" smd rect
			(at -2.050034 -37.824918 270)
			(size 0.519938 1.4986)
			(layers "F.Cu" "F.Mask" "F.Paste")
			(net "M_A_CPU0_SA_DQ<17>")
		)
		(pad "32" smd rect
			(at -2.050034 -36.975034 270)
			(size 0.519938 1.4986)
			(layers "F.Cu" "F.Mask" "F.Paste")
			(net "GND")
		)
		(pad "33" smd rect
			(at -2.050034 -36.124896 270)
			(size 0.519938 1.4986)
			(layers "F.Cu" "F.Mask" "F.Paste")
			(net "M_A_CPU0_SA_DQS_DP<2>")
		)
		(pad "34" smd rect
			(at -2.050034 -35.275012 270)
			(size 0.519938 1.4986)
			(layers "F.Cu" "F.Mask" "F.Paste")
			(net "M_A_CPU0_SA_DQS_DN<2>")
		)
		(pad "35" smd rect
			(at -2.050034 -34.425128 270)
			(size 0.519938 1.4986)
			(layers "F.Cu" "F.Mask" "F.Paste")
			(net "GND")
		)
		(pad "36" smd rect
			(at -2.050034 -33.57499 270)
			(size 0.519938 1.4986)
			(layers "F.Cu" "F.Mask" "F.Paste")
			(net "M_A_CPU0_SA_DQ<20>")
		)
		(pad "37" smd rect
			(at -2.050034 -32.725106 270)
			(size 0.519938 1.4986)
			(layers "F.Cu" "F.Mask" "F.Paste")
			(net "GND")
		)
		(pad "38" smd rect
			(at -2.050034 -31.874968 270)
			(size 0.519938 1.4986)
			(layers "F.Cu" "F.Mask" "F.Paste")
			(net "M_A_CPU0_SA_DQ<21>")
		)
		(pad "39" smd rect
			(at -2.050034 -31.025084 270)
			(size 0.519938 1.4986)
			(layers "F.Cu" "F.Mask" "F.Paste")
			(net "GND")
		)
		(pad "40" smd rect
			(at -2.050034 -30.174946 270)
			(size 0.519938 1.4986)
			(layers "F.Cu" "F.Mask" "F.Paste")
			(net "M_A_CPU0_SA_DQ<24>")
		)
		(pad "41" smd rect
			(at -2.050034 -29.325062 270)
			(size 0.519938 1.4986)
			(layers "F.Cu" "F.Mask" "F.Paste")
			(net "GND")
		)
		(pad "42" smd rect
			(at -2.050034 -28.474924 270)
			(size 0.519938 1.4986)
			(layers "F.Cu" "F.Mask" "F.Paste")
			(net "M_A_CPU0_SA_DQ<25>")
		)
		(pad "43" smd rect
			(at -2.050034 -27.62504 270)
			(size 0.519938 1.4986)
			(layers "F.Cu" "F.Mask" "F.Paste")
			(net "GND")
		)
		(pad "44" smd rect
			(at -2.050034 -26.774902 270)
			(size 0.519938 1.4986)
			(layers "F.Cu" "F.Mask" "F.Paste")
			(net "M_A_CPU0_SA_DQS_DP<3>")
		)
		(pad "45" smd rect
			(at -2.050034 -25.925018 270)
			(size 0.519938 1.4986)
			(layers "F.Cu" "F.Mask" "F.Paste")
			(net "M_A_CPU0_SA_DQS_DN<3>")
		)
		(pad "46" smd rect
			(at -2.050034 -25.07488 270)
			(size 0.519938 1.4986)
			(layers "F.Cu" "F.Mask" "F.Paste")
			(net "GND")
		)
		(pad "47" smd rect
			(at -2.050034 -24.224996 270)
			(size 0.519938 1.4986)
			(layers "F.Cu" "F.Mask" "F.Paste")
			(net "M_A_CPU0_SA_DQ<28>")
		)
		(pad "48" smd rect
			(at -2.050034 -23.375112 270)
			(size 0.519938 1.4986)
			(layers "F.Cu" "F.Mask" "F.Paste")
			(net "GND")
		)
		(pad "49" smd rect
			(at -2.050034 -22.524974 270)
			(size 0.519938 1.4986)
			(layers "F.Cu" "F.Mask" "F.Paste")
			(net "M_A_CPU0_SA_DQ<29>")
		)
		(pad "50" smd rect
			(at -2.050034 -21.67509 270)
			(size 0.519938 1.4986)
			(layers "F.Cu" "F.Mask" "F.Paste")
			(net "GND")
		)
		(pad "51" smd rect
			(at -2.050034 -20.824952 270)
			(size 0.519938 1.4986)
			(layers "F.Cu" "F.Mask" "F.Paste")
			(net "M_A_CPU0_SA_CB<0>")
		)
		(pad "52" smd rect
			(at -2.050034 -19.975068 270)
			(size 0.519938 1.4986)
			(layers "F.Cu" "F.Mask" "F.Paste")
			(net "GND")
		)
		(pad "53" smd rect
			(at -2.050034 -19.12493 270)
			(size 0.519938 1.4986)
			(layers "F.Cu" "F.Mask" "F.Paste")
			(net "M_A_CPU0_SA_CB<1>")
		)
		(pad "54" smd rect
			(at -2.050034 -18.275046 270)
			(size 0.519938 1.4986)
			(layers "F.Cu" "F.Mask" "F.Paste")
			(net "GND")
		)
		(pad "55" smd rect
			(at -2.050034 -17.424908 270)
			(size 0.519938 1.4986)
			(layers "F.Cu" "F.Mask" "F.Paste")
			(net "M_A_CPU0_SA_DQS_DP<4>")
		)
		(pad "56" smd rect
			(at -2.050034 -16.575024 270)
			(size 0.519938 1.4986)
			(layers "F.Cu" "F.Mask" "F.Paste")
			(net "M_A_CPU0_SA_DQS_DN<4>")
		)
		(pad "57" smd rect
			(at -2.050034 -15.724886 270)
			(size 0.519938 1.4986)
			(layers "F.Cu" "F.Mask" "F.Paste")
			(net "GND")
		)
		(pad "58" smd rect
			(at -2.050034 -14.875002 270)
			(size 0.519938 1.4986)
			(layers "F.Cu" "F.Mask" "F.Paste")
			(net "M_A_CPU0_SA_CB<4>")
		)
		(pad "59" smd rect
			(at -2.050034 -14.025118 270)
			(size 0.519938 1.4986)
			(layers "F.Cu" "F.Mask" "F.Paste")
			(net "GND")
		)
		(pad "60" smd rect
			(at -2.050034 -13.17498 270)
			(size 0.519938 1.4986)
			(layers "F.Cu" "F.Mask" "F.Paste")
			(net "M_A_CPU0_SA_CB<5>")
		)
		(pad "61" smd rect
			(at -2.050034 -12.325096 270)
			(size 0.519938 1.4986)
			(layers "F.Cu" "F.Mask" "F.Paste")
			(net "GND")
		)
		(pad "62" smd rect
			(at -2.050034 -11.474958 270)
			(size 0.519938 1.4986)
			(layers "F.Cu" "F.Mask" "F.Paste")
			(net "M_A_CPU0_ALERT_N")
		)
		(pad "63" smd rect
			(at -2.050034 -10.625074 270)
			(size 0.519938 1.4986)
			(layers "F.Cu" "F.Mask" "F.Paste")
			(net "GND")
		)
		(pad "64" smd rect
			(at -2.050034 -9.774936 270)
			(size 0.519938 1.4986)
			(layers "F.Cu" "F.Mask" "F.Paste")
			(net "M_A_CPU0_SA_CS_N<0>")
		)
		(pad "65" smd rect
			(at -2.050034 -8.925052 270)
			(size 0.519938 1.4986)
			(layers "F.Cu" "F.Mask" "F.Paste")
			(net "GND")
		)
		(pad "66" smd rect
			(at -2.050034 -8.074914 270)
			(size 0.519938 1.4986)
			(layers "F.Cu" "F.Mask" "F.Paste")
			(net "M_A_CPU0_SA_CA<0>")
		)
		(pad "67" smd rect
			(at -2.050034 -7.22503 270)
			(size 0.519938 1.4986)
			(layers "F.Cu" "F.Mask" "F.Paste")
			(net "GND")
		)
		(pad "68" smd rect
			(at -2.050034 -6.374892 270)
			(size 0.519938 1.4986)
			(layers "F.Cu" "F.Mask" "F.Paste")
			(net "M_A_CPU0_SA_CA<2>")
		)
		(pad "69" smd rect
			(at -2.050034 -5.525008 270)
			(size 0.519938 1.4986)
			(layers "F.Cu" "F.Mask" "F.Paste")
			(net "GND")
		)
		(pad "70" smd rect
			(at -2.050034 -4.675124 270)
			(size 0.519938 1.4986)
			(layers "F.Cu" "F.Mask" "F.Paste")
			(net "M_A_CPU0_SA_CA<4>")
		)
		(pad "71" smd rect
			(at -2.050034 -3.824986 270)
			(size 0.519938 1.4986)
			(layers "F.Cu" "F.Mask" "F.Paste")
			(net "GND")
		)
		(pad "72" smd rect
			(at -2.050034 -2.975102 270)
			(size 0.519938 1.4986)
			(layers "F.Cu" "F.Mask" "F.Paste")
			(net "M_A_CPU0_SA_CA<6>")
		)
		(pad "73" smd rect
			(at -2.050034 -2.124964 270)
			(size 0.519938 1.4986)
			(layers "F.Cu" "F.Mask" "F.Paste")
			(net "GND")
		)
		(pad "74" smd rect
			(at -2.050034 -1.27508 270)
			(size 0.519938 1.4986)
			(layers "F.Cu" "F.Mask" "F.Paste")
			(net "M_A_CPU0_SA_PAR")
		)
		(pad "75" smd rect
			(at -2.050034 -0.424942 270)
			(size 0.519938 1.4986)
			(layers "F.Cu" "F.Mask" "F.Paste")
			(net "GND")
		)
		(pad "76" smd rect
			(at -2.050034 5.525008 270)
			(size 0.519938 1.4986)
			(layers "F.Cu" "F.Mask" "F.Paste")
			(net "M_A_CPU0_SB_CA<0>")
		)
		(pad "77" smd rect
			(at -2.050034 6.374892 270)
			(size 0.519938 1.4986)
			(layers "F.Cu" "F.Mask" "F.Paste")
			(net "GND")
		)
		(pad "78" smd rect
			(at -2.050034 7.22503 270)
			(size 0.519938 1.4986)
			(layers "F.Cu" "F.Mask" "F.Paste")
			(net "M_A_CPU0_SB_CA<2>")
		)
		(pad "79" smd rect
			(at -2.050034 8.074914 270)
			(size 0.519938 1.4986)
			(layers "F.Cu" "F.Mask" "F.Paste")
			(net "GND")
		)
		(pad "80" smd rect
			(at -2.050034 8.925052 270)
			(size 0.519938 1.4986)
			(layers "F.Cu" "F.Mask" "F.Paste")
			(net "M_A_CPU0_SB_CA<4>")
		)
		(pad "81" smd rect
			(at -2.050034 9.774936 270)
			(size 0.519938 1.4986)
			(layers "F.Cu" "F.Mask" "F.Paste")
			(net "GND")
		)
		(pad "82" smd rect
			(at -2.050034 10.625074 270)
			(size 0.519938 1.4986)
			(layers "F.Cu" "F.Mask" "F.Paste")
			(net "M_A_CPU0_SB_CA<6>")
		)
		(pad "83" smd rect
			(at -2.050034 11.474958 270)
			(size 0.519938 1.4986)
			(layers "F.Cu" "F.Mask" "F.Paste")
			(net "GND")
		)
		(pad "84" smd rect
			(at -2.050034 12.325096 270)
			(size 0.519938 1.4986)
			(layers "F.Cu" "F.Mask" "F.Paste")
			(net "M_A_CPU0_SB_CS_N<0>")
		)
		(pad "85" smd rect
			(at -2.050034 13.17498 270)
			(size 0.519938 1.4986)
			(layers "F.Cu" "F.Mask" "F.Paste")
			(net "GND")
		)
		(pad "86" smd rect
			(at -2.050034 14.025118 270)
			(size 0.519938 1.4986)
			(layers "F.Cu" "F.Mask" "F.Paste")
			(net "M_A_CPU0_SA_RSP<0>")
		)
		(pad "87" smd rect
			(at -2.050034 14.875002 270)
			(size 0.519938 1.4986)
			(layers "F.Cu" "F.Mask" "F.Paste")
			(net "M_A_CPU0_SB_RSP<0>")
		)
		(pad "88" smd rect
			(at -2.050034 15.724886 270)
			(size 0.519938 1.4986)
			(layers "F.Cu" "F.Mask" "F.Paste")
			(net "GND")
		)
		(pad "89" smd rect
			(at -2.050034 16.575024 270)
			(size 0.519938 1.4986)
			(layers "F.Cu" "F.Mask" "F.Paste")
			(net "M_A_CPU0_SB_CB<4>")
		)
		(pad "90" smd rect
			(at -2.050034 17.424908 270)
			(size 0.519938 1.4986)
			(layers "F.Cu" "F.Mask" "F.Paste")
			(net "GND")
		)
		(pad "91" smd rect
			(at -2.050034 18.275046 270)
			(size 0.519938 1.4986)
			(layers "F.Cu" "F.Mask" "F.Paste")
			(net "M_A_CPU0_SB_CB<5>")
		)
		(pad "92" smd rect
			(at -2.050034 19.12493 270)
			(size 0.519938 1.4986)
			(layers "F.Cu" "F.Mask" "F.Paste")
			(net "GND")
		)
		(pad "93" smd rect
			(at -2.050034 19.975068 270)
			(size 0.519938 1.4986)
			(layers "F.Cu" "F.Mask" "F.Paste")
			(net "M_A_CPU0_SB_DQS_DP<9>")
		)
		(pad "94" smd rect
			(at -2.050034 20.824952 270)
			(size 0.519938 1.4986)
			(layers "F.Cu" "F.Mask" "F.Paste")
			(net "M_A_CPU0_SB_DQS_DN<9>")
		)
		(pad "95" smd rect
			(at -2.050034 21.67509 270)
			(size 0.519938 1.4986)
			(layers "F.Cu" "F.Mask" "F.Paste")
			(net "GND")
		)
		(pad "96" smd rect
			(at -2.050034 22.524974 270)
			(size 0.519938 1.4986)
			(layers "F.Cu" "F.Mask" "F.Paste")
			(net "M_A_CPU0_SB_CB<0>")
		)
		(pad "97" smd rect
			(at -2.050034 23.375112 270)
			(size 0.519938 1.4986)
			(layers "F.Cu" "F.Mask" "F.Paste")
			(net "GND")
		)
		(pad "98" smd rect
			(at -2.050034 24.224996 270)
			(size 0.519938 1.4986)
			(layers "F.Cu" "F.Mask" "F.Paste")
			(net "M_A_CPU0_SB_CB<1>")
		)
		(pad "99" smd rect
			(at -2.050034 25.07488 270)
			(size 0.519938 1.4986)
			(layers "F.Cu" "F.Mask" "F.Paste")
			(net "GND")
		)
		(pad "100" smd rect
			(at -2.050034 25.925018 270)
			(size 0.519938 1.4986)
			(layers "F.Cu" "F.Mask" "F.Paste")
			(net "M_A_CPU0_SB_DQ<0>")
		)
		(pad "101" smd rect
			(at -2.050034 26.774902 270)
			(size 0.519938 1.4986)
			(layers "F.Cu" "F.Mask" "F.Paste")
			(net "GND")
		)
		(pad "102" smd rect
			(at -2.050034 27.62504 270)
			(size 0.519938 1.4986)
			(layers "F.Cu" "F.Mask" "F.Paste")
			(net "M_A_CPU0_SB_DQ<1>")
		)
		(pad "103" smd rect
			(at -2.050034 28.474924 270)
			(size 0.519938 1.4986)
			(layers "F.Cu" "F.Mask" "F.Paste")
			(net "GND")
		)
		(pad "104" smd rect
			(at -2.050034 29.325062 270)
			(size 0.519938 1.4986)
			(layers "F.Cu" "F.Mask" "F.Paste")
			(net "M_A_CPU0_SB_DQS_DP<0>")
		)
		(pad "105" smd rect
			(at -2.050034 30.174946 270)
			(size 0.519938 1.4986)
			(layers "F.Cu" "F.Mask" "F.Paste")
			(net "M_A_CPU0_SB_DQS_DN<0>")
		)
		(pad "106" smd rect
			(at -2.050034 31.025084 270)
			(size 0.519938 1.4986)
			(layers "F.Cu" "F.Mask" "F.Paste")
			(net "GND")
		)
		(pad "107" smd rect
			(at -2.050034 31.874968 270)
			(size 0.519938 1.4986)
			(layers "F.Cu" "F.Mask" "F.Paste")
			(net "M_A_CPU0_SB_DQ<4>")
		)
		(pad "108" smd rect
			(at -2.050034 32.725106 270)
			(size 0.519938 1.4986)
			(layers "F.Cu" "F.Mask" "F.Paste")
			(net "GND")
		)
		(pad "109" smd rect
			(at -2.050034 33.57499 270)
			(size 0.519938 1.4986)
			(layers "F.Cu" "F.Mask" "F.Paste")
			(net "M_A_CPU0_SB_DQ<5>")
		)
		(pad "110" smd rect
			(at -2.050034 34.425128 270)
			(size 0.519938 1.4986)
			(layers "F.Cu" "F.Mask" "F.Paste")
			(net "GND")
		)
		(pad "111" smd rect
			(at -2.050034 35.275012 270)
			(size 0.519938 1.4986)
			(layers "F.Cu" "F.Mask" "F.Paste")
			(net "M_A_CPU0_SB_DQ<8>")
		)
		(pad "112" smd rect
			(at -2.050034 36.124896 270)
			(size 0.519938 1.4986)
			(layers "F.Cu" "F.Mask" "F.Paste")
			(net "GND")
		)
	)
)
